(kicad_pcb
	(version 20260206)
	(generator "pcbnew")
	(generator_version "10.0")
	(general
		(thickness 1.6)
		(legacy_teardrops no)
	)
	(paper "A4")
	(title_block
		(title "timecard-production-celestica-r4006 — R4006-B0001-02_R01.brd")
		(comment 1 "Time Appliance Project (Time Card) / footprints 328-332 of 1113")
	)
	(layers
		(0 "F.Cu" signal "TOP")
		(4 "In1.Cu" signal "L02_GND1")
		(6 "In2.Cu" signal "L03_SIG1")
		(8 "In3.Cu" signal "L04_GND2")
		(10 "In4.Cu" signal "L05_VCC1")
		(12 "In5.Cu" signal "L06_VCC2")
		(14 "In6.Cu" signal "L07_GND3")
		(16 "In7.Cu" signal "L08_SIG2")
		(18 "In8.Cu" signal "L09_GND4")
		(2 "B.Cu" signal "BOTTOM")
		(9 "F.Adhes" user "F.Adhesive")
		(11 "B.Adhes" user "B.Adhesive")
		(13 "F.Paste" user "Package Geometry/Pastemask Top")
		(15 "B.Paste" user "Package Geometry/Pastemask Bottom")
		(5 "F.SilkS" user "Ref Des/Silkscreen Top")
		(7 "B.SilkS" user "Ref Des/Silkscreen Bottom")
		(1 "F.Mask" user "Board Geometry/Soldermask Top")
		(3 "B.Mask" user "Board Geometry/Soldermask Bottom")
		(17 "Dwgs.User" user "User.Drawings")
		(19 "Cmts.User" user "User.Comments")
		(21 "Eco1.User" user "User.Eco1")
		(23 "Eco2.User" user "User.Eco2")
		(25 "Edge.Cuts" user "Board Geometry/Outline")
		(27 "Margin" user)
		(31 "F.CrtYd" user "Package Geometry/Place Bound Top")
		(29 "B.CrtYd" user "Package Geometry/Place Bound Bottom")
		(35 "F.Fab" user "Ref Des/Assembly Top")
		(33 "B.Fab" user "Ref Des/Assembly Bottom")
	)
	(footprint ""
		(layer "F.Cu")
		(at 8.2804 -39.318692 90)
		(property "Reference" "R387"
			(at 2.337308 -0.04445 90)
			(unlocked yes)
			(layer "F.SilkS")
			(effects
				(font
					(size 0.635 0.4064)
					(thickness 0.1524)
				)
			)
		)
		(property "Value" "VAL*"
			(at 0.02032 2.13233 90)
			(unlocked yes)
			(layer "F.Fab")
			(hide yes)
			(effects
				(font
					(size 0.7874 0.5842)
					(thickness 0.1524)
				)
			)
		)
		(property "Tolerance" "TOL*"
			(at 0.044704 3.05435 90)
			(unlocked yes)
			(layer "Cmts.User")
			(hide yes)
			(effects
				(font
					(size 0.7874 0.5842)
					(thickness 0.1524)
				)
			)
		)
		(property "User Part Number" "PARTNUM*"
			(at 0.02032 4.024884 90)
			(unlocked yes)
			(layer "Cmts.User")
			(hide yes)
			(effects
				(font
					(size 0.7874 0.5842)
					(thickness 0.1524)
				)
			)
		)
		(property "Device Type" "RESISTOR-G155-133R0-01,33OHM,1%"
			(at 0.008382 1.210564 90)
			(unlocked yes)
			(layer "F.Fab")
			(hide yes)
			(effects
				(font
					(size 0.7874 0.5842)
					(thickness 0.1524)
				)
			)
		)
		(duplicate_pad_numbers_are_jumpers no)
		(fp_line
			(start 1.143 -0.5588)
			(end -1.143 -0.5588)
			(stroke
				(width 0.1)
				(type default)
			)
			(layer "F.SilkS")
		)
		(fp_line
			(start -1.143 -0.5588)
			(end -1.143 0.5588)
			(stroke
				(width 0.1)
				(type default)
			)
			(layer "F.SilkS")
		)
		(fp_line
			(start 1.143 0.5588)
			(end 1.143 -0.5588)
			(stroke
				(width 0.1)
				(type default)
			)
			(layer "F.SilkS")
		)
		(fp_line
			(start -1.143 0.5588)
			(end 1.143 0.5588)
			(stroke
				(width 0.1)
				(type default)
			)
			(layer "F.SilkS")
		)
		(fp_rect
			(start -1.143 -0.5588)
			(end 1.143 0.5588)
			(stroke
				(width 0)
				(type default)
			)
			(fill no)
			(layer "F.CrtYd")
		)
		(fp_line
			(start 0.508 -0.3048)
			(end -0.508 -0.3048)
			(stroke
				(width 0.1)
				(type default)
			)
			(layer "F.Fab")
		)
		(fp_line
			(start -0.508 -0.3048)
			(end -0.508 0.3048)
			(stroke
				(width 0.1)
				(type default)
			)
			(layer "F.Fab")
		)
		(fp_line
			(start 0.508 0.3048)
			(end 0.508 -0.3048)
			(stroke
				(width 0.1)
				(type default)
			)
			(layer "F.Fab")
		)
		(fp_line
			(start -0.508 0.3048)
			(end 0.508 0.3048)
			(stroke
				(width 0.1)
				(type default)
			)
			(layer "F.Fab")
		)
		(pad "1" smd rect
			(at -0.5334 0 90)
			(size 0.7112 0.6096)
			(layers "F.Cu" "F.Mask" "F.Paste")
			(net "SMA1_LED_RED_N")
		)
		(pad "2" smd rect
			(at 0.5334 0 90)
			(size 0.7112 0.6096)
			(layers "F.Cu" "F.Mask" "F.Paste")
			(net "UNNAMED_14_LED4PV14_I265_3")
		)
		(zone
			(layer "F.Cu")
			(hatch none 0.5)
			(connect_pads
				(clearance 0)
			)
			(min_thickness 0.25)
			(keepout
				(tracks not_allowed)
				(vias allowed)
				(pads allowed)
				(copperpour not_allowed)
				(footprints allowed)
			)
			(placement
				(enabled no)
				(sheetname "")
			)
			(fill
				(thermal_gap 0.5)
				(thermal_bridge_width 0.5)
				(island_removal_mode 0)
			)
			(polygon
				(pts
					(xy 7.9756 -39.242492) (xy 8.5852 -39.242492) (xy 8.5852 -39.394892) (xy 7.9756 -39.394892)
				)
			)
		)
		(zone
			(layer "F.Cu")
			(hatch none 0.5)
			(connect_pads
				(clearance 0)
			)
			(min_thickness 0.25)
			(keepout
				(tracks allowed)
				(vias not_allowed)
				(pads allowed)
				(copperpour not_allowed)
				(footprints allowed)
			)
			(placement
				(enabled no)
				(sheetname "")
			)
			(fill
				(thermal_gap 0.5)
				(thermal_bridge_width 0.5)
				(island_removal_mode 0)
			)
			(polygon
				(pts
					(xy 7.9756 -39.242492) (xy 8.5852 -39.242492) (xy 8.5852 -39.394892) (xy 7.9756 -39.394892)
				)
			)
		)
	)
	(footprint ""
		(layer "F.Cu")
		(at 81.0006 -51.181 180)
		(property "Reference" "R85"
			(at 0.9906 -14.88567 0)
			(unlocked yes)
			(layer "F.SilkS")
			(effects
				(font
					(size 0.7874 0.5842)
					(thickness 0.1524)
				)
			)
		)
		(property "Value" "VAL*"
			(at 0.02032 2.13233 180)
			(unlocked yes)
			(layer "F.Fab")
			(hide yes)
			(effects
				(font
					(size 0.7874 0.5842)
					(thickness 0.1524)
				)
			)
		)
		(property "Tolerance" "TOL*"
			(at 0.044704 3.05435 180)
			(unlocked yes)
			(layer "Cmts.User")
			(hide yes)
			(effects
				(font
					(size 0.7874 0.5842)
					(thickness 0.1524)
				)
			)
		)
		(property "User Part Number" "PARTNUM*"
			(at 0.02032 4.024884 180)
			(unlocked yes)
			(layer "Cmts.User")
			(hide yes)
			(effects
				(font
					(size 0.7874 0.5842)
					(thickness 0.1524)
				)
			)
		)
		(property "Device Type" "RESISTOR-G155-100R0-J0,0OHM,-"
			(at 0.008382 1.210564 180)
			(unlocked yes)
			(layer "F.Fab")
			(hide yes)
			(effects
				(font
					(size 0.7874 0.5842)
					(thickness 0.1524)
				)
			)
		)
		(duplicate_pad_numbers_are_jumpers no)
		(fp_line
			(start 1.143 0.5588)
			(end 1.143 -0.5588)
			(stroke
				(width 0.1)
				(type default)
			)
			(layer "F.SilkS")
		)
		(fp_line
			(start 1.143 -0.5588)
			(end -1.143 -0.5588)
			(stroke
				(width 0.1)
				(type default)
			)
			(layer "F.SilkS")
		)
		(fp_line
			(start -1.143 0.5588)
			(end 1.143 0.5588)
			(stroke
				(width 0.1)
				(type default)
			)
			(layer "F.SilkS")
		)
		(fp_line
			(start -1.143 -0.5588)
			(end -1.143 0.5588)
			(stroke
				(width 0.1)
				(type default)
			)
			(layer "F.SilkS")
		)
		(fp_rect
			(start 1.143 -0.5588)
			(end -1.143 0.5588)
			(stroke
				(width 0)
				(type default)
			)
			(fill no)
			(layer "F.CrtYd")
		)
		(fp_line
			(start 0.508 0.3048)
			(end 0.508 -0.3048)
			(stroke
				(width 0.1)
				(type default)
			)
			(layer "F.Fab")
		)
		(fp_line
			(start 0.508 -0.3048)
			(end -0.508 -0.3048)
			(stroke
				(width 0.1)
				(type default)
			)
			(layer "F.Fab")
		)
		(fp_line
			(start -0.508 0.3048)
			(end 0.508 0.3048)
			(stroke
				(width 0.1)
				(type default)
			)
			(layer "F.Fab")
		)
		(fp_line
			(start -0.508 -0.3048)
			(end -0.508 0.3048)
			(stroke
				(width 0.1)
				(type default)
			)
			(layer "F.Fab")
		)
		(pad "1" smd rect
			(at -0.5334 0 180)
			(size 0.7112 0.6096)
			(layers "F.Cu" "F.Mask" "F.Paste")
			(net "FPGA_OUT_MAC_PPS_IN0P")
		)
		(pad "2" smd rect
			(at 0.5334 0 180)
			(size 0.7112 0.6096)
			(layers "F.Cu" "F.Mask" "F.Paste")
			(net "R_MAC_PPS_IN0P")
		)
		(zone
			(layer "F.Cu")
			(hatch none 0.5)
			(connect_pads
				(clearance 0)
			)
			(min_thickness 0.25)
			(keepout
				(tracks allowed)
				(vias not_allowed)
				(pads allowed)
				(copperpour not_allowed)
				(footprints allowed)
			)
			(placement
				(enabled no)
				(sheetname "")
			)
			(fill
				(thermal_gap 0.5)
				(thermal_bridge_width 0.5)
				(island_removal_mode 0)
			)
			(polygon
				(pts
					(xy 80.9244 -50.8762) (xy 81.0768 -50.8762) (xy 81.0768 -51.4858) (xy 80.9244 -51.4858)
				)
			)
		)
	)
	(footprint ""
		(layer "F.Cu")
		(at 111.125 -103.251 180)
		(property "Reference" "R364"
			(at -3.175 3.26263 0)
			(unlocked yes)
			(layer "F.SilkS")
			(effects
				(font
					(size 0.7874 0.5842)
					(thickness 0.1524)
				)
			)
		)
		(property "Value" "VAL*"
			(at 0.02032 2.13233 180)
			(unlocked yes)
			(layer "F.Fab")
			(hide yes)
			(effects
				(font
					(size 0.7874 0.5842)
					(thickness 0.1524)
				)
			)
		)
		(property "Tolerance" "TOL*"
			(at 0.044704 3.05435 180)
			(unlocked yes)
			(layer "Cmts.User")
			(hide yes)
			(effects
				(font
					(size 0.7874 0.5842)
					(thickness 0.1524)
				)
			)
		)
		(property "User Part Number" "PARTNUM*"
			(at 0.02032 4.024884 180)
			(unlocked yes)
			(layer "Cmts.User")
			(hide yes)
			(effects
				(font
					(size 0.7874 0.5842)
					(thickness 0.1524)
				)
			)
		)
		(property "Device Type" "RESISTOR-G155-133R0-01,33OHM,1%"
			(at 0.008382 1.210564 180)
			(unlocked yes)
			(layer "F.Fab")
			(hide yes)
			(effects
				(font
					(size 0.7874 0.5842)
					(thickness 0.1524)
				)
			)
		)
		(duplicate_pad_numbers_are_jumpers no)
		(fp_line
			(start 1.143 0.5588)
			(end 1.143 -0.5588)
			(stroke
				(width 0.1)
				(type default)
			)
			(layer "F.SilkS")
		)
		(fp_line
			(start 1.143 -0.5588)
			(end -1.143 -0.5588)
			(stroke
				(width 0.1)
				(type default)
			)
			(layer "F.SilkS")
		)
		(fp_line
			(start -1.143 0.5588)
			(end 1.143 0.5588)
			(stroke
				(width 0.1)
				(type default)
			)
			(layer "F.SilkS")
		)
		(fp_line
			(start -1.143 -0.5588)
			(end -1.143 0.5588)
			(stroke
				(width 0.1)
				(type default)
			)
			(layer "F.SilkS")
		)
		(fp_poly
			(pts
				(xy -1.143 0.5588) (xy 1.143 0.5588) (xy 1.143 -0.5588) (xy -1.143 -0.5588)
			)
			(stroke
				(width 0)
				(type default)
			)
			(fill no)
			(layer "F.CrtYd")
		)
		(fp_line
			(start 0.508 0.3048)
			(end 0.508 -0.3048)
			(stroke
				(width 0.1)
				(type default)
			)
			(layer "F.Fab")
		)
		(fp_line
			(start 0.508 -0.3048)
			(end -0.508 -0.3048)
			(stroke
				(width 0.1)
				(type default)
			)
			(layer "F.Fab")
		)
		(fp_line
			(start -0.508 0.3048)
			(end 0.508 0.3048)
			(stroke
				(width 0.1)
				(type default)
			)
			(layer "F.Fab")
		)
		(fp_line
			(start -0.508 -0.3048)
			(end -0.508 0.3048)
			(stroke
				(width 0.1)
				(type default)
			)
			(layer "F.Fab")
		)
		(pad "1" smd rect
			(at -0.5334 0 180)
			(size 0.7112 0.6096)
			(layers "F.Cu" "F.Mask" "F.Paste")
			(net "RGB_LED_I2C_SDA")
		)
		(pad "2" smd rect
			(at 0.5334 0 180)
			(size 0.7112 0.6096)
			(layers "F.Cu" "F.Mask" "F.Paste")
			(net "R_RGB_LED_I2C_SDA")
		)
		(zone
			(layer "F.Cu")
			(hatch none 0.5)
			(connect_pads
				(clearance 0)
			)
			(min_thickness 0.25)
			(keepout
				(tracks allowed)
				(vias not_allowed)
				(pads allowed)
				(copperpour not_allowed)
				(footprints allowed)
			)
			(placement
				(enabled no)
				(sheetname "")
			)
			(fill
				(thermal_gap 0.5)
				(thermal_bridge_width 0.5)
				(island_removal_mode 0)
			)
			(polygon
				(pts
					(xy 111.2012 -103.5558) (xy 111.0488 -103.5558) (xy 111.0488 -102.9462) (xy 111.2012 -102.9462)
				)
			)
		)
		(zone
			(layer "F.Cu")
			(hatch none 0.5)
			(connect_pads
				(clearance 0)
			)
			(min_thickness 0.25)
			(keepout
				(tracks not_allowed)
				(vias allowed)
				(pads allowed)
				(copperpour not_allowed)
				(footprints allowed)
			)
			(placement
				(enabled no)
				(sheetname "")
			)
			(fill
				(thermal_gap 0.5)
				(thermal_bridge_width 0.5)
				(island_removal_mode 0)
			)
			(polygon
				(pts
					(xy 111.2012 -103.5558) (xy 111.0488 -103.5558) (xy 111.0488 -102.9462) (xy 111.2012 -102.9462)
				)
			)
		)
	)
	(footprint ""
		(layer "F.Cu")
		(at 33.7693 -15.5702 180)
		(property "Reference" "R183"
			(at -2.6543 -2.07137 0)
			(unlocked yes)
			(layer "F.SilkS")
			(effects
				(font
					(size 0.7874 0.5842)
					(thickness 0.1524)
				)
			)
		)
		(property "Value" "VAL*"
			(at 0.02032 2.13233 180)
			(unlocked yes)
			(layer "F.Fab")
			(hide yes)
			(effects
				(font
					(size 0.7874 0.5842)
					(thickness 0.1524)
				)
			)
		)
		(property "Tolerance" "TOL*"
			(at 0.044704 3.05435 180)
			(unlocked yes)
			(layer "Cmts.User")
			(hide yes)
			(effects
				(font
					(size 0.7874 0.5842)
					(thickness 0.1524)
				)
			)
		)
		(property "User Part Number" "PARTNUM*"
			(at 0.02032 4.024884 180)
			(unlocked yes)
			(layer "Cmts.User")
			(hide yes)
			(effects
				(font
					(size 0.7874 0.5842)
					(thickness 0.1524)
				)
			)
		)
		(property "Device Type" "RESISTOR-G155-133R0-01,33OHM,1%"
			(at 0.008382 1.210564 180)
			(unlocked yes)
			(layer "F.Fab")
			(hide yes)
			(effects
				(font
					(size 0.7874 0.5842)
					(thickness 0.1524)
				)
			)
		)
		(duplicate_pad_numbers_are_jumpers no)
		(fp_line
			(start 1.143 0.5588)
			(end 1.143 -0.5588)
			(stroke
				(width 0.1)
				(type default)
			)
			(layer "F.SilkS")
		)
		(fp_line
			(start 1.143 -0.5588)
			(end -1.143 -0.5588)
			(stroke
				(width 0.1)
				(type default)
			)
			(layer "F.SilkS")
		)
		(fp_line
			(start -1.143 0.5588)
			(end 1.143 0.5588)
			(stroke
				(width 0.1)
				(type default)
			)
			(layer "F.SilkS")
		)
		(fp_line
			(start -1.143 -0.5588)
			(end -1.143 0.5588)
			(stroke
				(width 0.1)
				(type default)
			)
			(layer "F.SilkS")
		)
		(fp_rect
			(start 1.143 -0.5588)
			(end -1.143 0.5588)
			(stroke
				(width 0)
				(type default)
			)
			(fill no)
			(layer "F.CrtYd")
		)
		(fp_line
			(start 0.508 0.3048)
			(end 0.508 -0.3048)
			(stroke
				(width 0.1)
				(type default)
			)
			(layer "F.Fab")
		)
		(fp_line
			(start 0.508 -0.3048)
			(end -0.508 -0.3048)
			(stroke
				(width 0.1)
				(type default)
			)
			(layer "F.Fab")
		)
		(fp_line
			(start -0.508 0.3048)
			(end 0.508 0.3048)
			(stroke
				(width 0.1)
				(type default)
			)
			(layer "F.Fab")
		)
		(fp_line
			(start -0.508 -0.3048)
			(end -0.508 0.3048)
			(stroke
				(width 0.1)
				(type default)
			)
			(layer "F.Fab")
		)
		(pad "1" smd rect
			(at -0.5334 0 180)
			(size 0.7112 0.6096)
			(layers "F.Cu" "F.Mask" "F.Paste")
			(net "EEPROM_I2C_SDA")
		)
		(pad "2" smd rect
			(at 0.5334 0 180)
			(size 0.7112 0.6096)
			(layers "F.Cu" "F.Mask" "F.Paste")
			(net "EEPROM_SDA")
		)
		(zone
			(layer "F.Cu")
			(hatch none 0.5)
			(connect_pads
				(clearance 0)
			)
			(min_thickness 0.25)
			(keepout
				(tracks allowed)
				(vias not_allowed)
				(pads allowed)
				(copperpour not_allowed)
				(footprints allowed)
			)
			(placement
				(enabled no)
				(sheetname "")
			)
			(fill
				(thermal_gap 0.5)
				(thermal_bridge_width 0.5)
				(island_removal_mode 0)
			)
			(polygon
				(pts
					(xy 33.6931 -15.2654) (xy 33.8455 -15.2654) (xy 33.8455 -15.875) (xy 33.6931 -15.875)
				)
			)
		)
	)
	(footprint ""
		(layer "F.Cu")
		(at 19.177 -38.735 180)
		(property "Reference" "J9"
			(at -3.556 1.61163 0)
			(unlocked yes)
			(layer "F.SilkS")
			(effects
				(font
					(size 0.7874 0.5842)
					(thickness 0.1524)
				)
			)
		)
		(property "Value" ""
			(at 0 0 180)
			(layer "F.Fab")
			(effects
				(font
					(size 1.27 1.27)
				)
			)
		)
		(property "User Part Number" "PARTNUM*"
			(at 0.069088 7.712456 180)
			(unlocked yes)
			(layer "Cmts.User")
			(hide yes)
			(effects
				(font
					(size 0.7874 0.5842)
					(thickness 0.000001)
				)
			)
		)
		(property "Device Type" "CONN_HDR_2X2_M_S_SMT-G200-1068A"
			(at 0.069088 6.518656 180)
			(unlocked yes)
			(layer "F.Fab")
			(hide yes)
			(effects
				(font
					(size 0.7874 0.5842)
					(thickness 0.000001)
				)
			)
		)
		(duplicate_pad_numbers_are_jumpers no)
		(fp_line
			(start 2.589022 4.637024)
			(end -2.589022 4.637024)
			(stroke
				(width 0.1)
				(type default)
			)
			(layer "F.SilkS")
		)
		(fp_line
			(start 2.589022 -4.637024)
			(end 2.589022 4.637024)
			(stroke
				(width 0.1)
				(type default)
			)
			(layer "F.SilkS")
		)
		(fp_line
			(start -2.589022 4.637024)
			(end -2.589022 -4.637024)
			(stroke
				(width 0.1)
				(type default)
			)
			(layer "F.SilkS")
		)
		(fp_line
			(start -2.589022 -4.637024)
			(end 2.589022 -4.637024)
			(stroke
				(width 0.1)
				(type default)
			)
			(layer "F.SilkS")
		)
		(fp_rect
			(start -2.843022 4.891024)
			(end 2.843022 -4.891024)
			(stroke
				(width 0)
				(type default)
			)
			(fill no)
			(layer "F.CrtYd")
		)
		(fp_line
			(start 2.335022 2.439924)
			(end 2.335022 -2.439924)
			(stroke
				(width 0.1)
				(type default)
			)
			(layer "F.Fab")
		)
		(fp_line
			(start 2.335022 -2.439924)
			(end -2.335022 -2.439924)
			(stroke
				(width 0.1)
				(type default)
			)
			(layer "F.Fab")
		)
		(fp_line
			(start -2.335022 2.439924)
			(end 2.335022 2.439924)
			(stroke
				(width 0.1)
				(type default)
			)
			(layer "F.Fab")
		)
		(fp_line
			(start -2.335022 -2.439924)
			(end -2.335022 2.439924)
			(stroke
				(width 0.1)
				(type default)
			)
			(layer "F.Fab")
		)
		(fp_text user "3"
			(at 1.8161 5.29463 0)
			(unlocked yes)
			(layer "F.SilkS")
			(effects
				(font
					(size 0.7874 0.5842)
					(thickness 0.1524)
				)
				(justify left)
			)
		)
		(fp_text user "4"
			(at 1.3081 -5.24637 0)
			(unlocked yes)
			(layer "F.SilkS")
			(effects
				(font
					(size 0.7874 0.5842)
					(thickness 0.1524)
				)
				(justify left)
			)
		)
		(fp_text user "1"
			(at -2.6289 4.27863 0)
			(unlocked yes)
			(layer "F.SilkS")
			(effects
				(font
					(size 0.7874 0.5842)
					(thickness 0.1524)
				)
				(justify left)
			)
		)
		(fp_text user "2"
			(at -2.8829 -3.34137 0)
			(unlocked yes)
			(layer "F.SilkS")
			(effects
				(font
					(size 0.7874 0.5842)
					(thickness 0.1524)
				)
				(justify left)
			)
		)
		(fp_text user "4"
			(at 1.770888 -3.285744 0)
			(unlocked yes)
			(layer "F.Fab")
			(effects
				(font
					(size 0.7874 0.5842)
					(thickness 0.1524)
				)
				(justify left)
			)
		)
		(fp_text user "3"
			(at 1.41478 3.674872 0)
			(unlocked yes)
			(layer "F.Fab")
			(effects
				(font
					(size 0.7874 0.5842)
					(thickness 0.1524)
				)
				(justify left)
			)
		)
		(fp_text user "2"
			(at -1.005332 -3.25247 0)
			(unlocked yes)
			(layer "F.Fab")
			(effects
				(font
					(size 0.7874 0.5842)
					(thickness 0.1524)
				)
				(justify left)
			)
		)
		(fp_text user "1"
			(at -1.22682 3.674872 0)
			(unlocked yes)
			(layer "F.Fab")
			(effects
				(font
					(size 0.7874 0.5842)
					(thickness 0.1524)
				)
				(justify left)
			)
		)
		(pad "1" smd rect
			(at -1.27 2.605024 180)
			(size 1.27 3.556)
			(layers "F.Cu" "F.Mask" "F.Paste")
			(net "UNNAMED_5_CONNHDR2X2MSSMT_I126_")
		)
		(pad "2" smd rect
			(at -1.27 -2.605024 180)
			(size 1.27 3.556)
			(layers "F.Cu" "F.Mask" "F.Paste")
			(net "EEPROM_SDA")
		)
		(pad "3" smd rect
			(at 1.27 2.605024 180)
			(size 1.27 3.556)
			(layers "F.Cu" "F.Mask" "F.Paste")
			(net "UNNAMED_5_CONNHDR2X2MSSMT_I12_1")
		)
		(pad "4" smd rect
			(at 1.27 -2.605024 180)
			(size 1.27 3.556)
			(layers "F.Cu" "F.Mask" "F.Paste")
			(net "EEPROM_SCL")
		)
	)
)
